# SCM (Grand Teton) — schematic netlist excerpt (pin names and nets, part order shuffled) for the footprints in the layout excerpt that follows; sources: Cadence DE-HDL packaged netlist, KiCad conversion of 12092022_DA0F0TMDCD0_F0T_Management_Board_D_brd_V3_OCP.brd

U41  RT9059GQW  IC  pkg DFN10_THXE  page 54
  VOUT1  = P1V8_AUX
  VOUT2  = P1V8_AUX
  VOUT3  = P1V8_AUX
  ADJ  = U41_ADJ
  PGOOD  = PWRGD_P1V8_AUX_R
  EN  = EN_P1V8_R
  VIN1  = P3V3_AUX
  VIN2  = P3V3_AUX
  VIN3  = P3V3_AUX
  VDD  = P5V_AUX
  EP  = GND

(kicad_pcb
	(version 20260206)
	(generator "pcbnew")
	(generator_version "10.0")
	(general
		(thickness 1.6)
		(legacy_teardrops no)
	)
	(paper "A4")
	(title_block
		(title "12092022_DA0F0TMDCD0_F0T_Management_Board_D_brd_V3_OCP.brd")
		(comment 1 "Grand Teton / footprints 558-558 of 1440")
	)
	(layers
		(0 "F.Cu" signal "TOP")
		(4 "In1.Cu" signal "GND")
		(6 "In2.Cu" signal "IN1")
		(8 "In3.Cu" signal "GND1")
		(10 "In4.Cu" signal "IN2")
		(12 "In5.Cu" signal "VCC")
		(14 "In6.Cu" signal "VCC1")
		(16 "In7.Cu" signal "IN3")
		(18 "In8.Cu" signal "GND2")
		(20 "In9.Cu" signal "IN4")
		(22 "In10.Cu" signal "GND3")
		(2 "B.Cu" signal "BOTTOM")
		(9 "F.Adhes" user "F.Adhesive")
		(11 "B.Adhes" user "B.Adhesive")
		(13 "F.Paste" user "Package Geometry/Pastemask Top")
		(15 "B.Paste" user "Package Geometry/Pastemask Bottom")
		(5 "F.SilkS" user "Ref Des/Silkscreen Top")
		(7 "B.SilkS" user "Ref Des/Silkscreen Bottom")
		(1 "F.Mask" user "Board Geometry/Soldermask Top")
		(3 "B.Mask" user "Board Geometry/Soldermask Bottom")
		(17 "Dwgs.User" user "User.Drawings")
		(19 "Cmts.User" user "User.Comments")
		(21 "Eco1.User" user "User.Eco1")
		(23 "Eco2.User" user "User.Eco2")
		(25 "Edge.Cuts" user "Board Geometry/Outline")
		(27 "Margin" user)
		(31 "F.CrtYd" user "Package Geometry/Place Bound Top")
		(29 "B.CrtYd" user "Package Geometry/Place Bound Bottom")
		(35 "F.Fab" user "Ref Des/Assembly Top")
		(33 "B.Fab" user "Ref Des/Assembly Bottom")
	)
	(footprint ""
		(layer "F.Cu")
		(at 36.668456 -55.936388 180)
		(property "Reference" "U41"
			(at 6.534912 -0.325628 0)
			(unlocked yes)
			(layer "F.SilkS")
			(effects
				(font
					(size 0.7874 0.5842)
					(thickness 0.1524)
				)
				(justify left)
			)
		)
		(property "Value" ""
			(at 0 0 180)
			(layer "F.Fab")
			(effects
				(font
					(size 1.27 1.27)
				)
			)
		)
		(duplicate_pad_numbers_are_jumpers no)
		(fp_line
			(start 1.525016 1.525016)
			(end 1.525016 1.3208)
			(stroke
				(width 0.1524)
				(type default)
			)
			(layer "F.SilkS")
		)
		(fp_line
			(start 1.525016 1.525016)
			(end -1.525016 1.525016)
			(stroke
				(width 0.1524)
				(type default)
			)
			(layer "F.SilkS")
		)
		(fp_line
			(start 1.525016 -1.3208)
			(end 1.525016 -1.525016)
			(stroke
				(width 0.1524)
				(type default)
			)
			(layer "F.SilkS")
		)
		(fp_line
			(start 1.525016 -1.525016)
			(end 0.9398 -1.525016)
			(stroke
				(width 0.1524)
				(type default)
			)
			(layer "F.SilkS")
		)
		(fp_line
			(start 1.525016 -1.525016)
			(end -1.525016 -1.525016)
			(stroke
				(width 0.1524)
				(type default)
			)
			(layer "F.SilkS")
		)
		(fp_line
			(start 0.9906 1.525016)
			(end 1.525016 1.525016)
			(stroke
				(width 0.1524)
				(type default)
			)
			(layer "F.SilkS")
		)
		(fp_line
			(start -0.8636 -1.525016)
			(end -1.525016 -1.525016)
			(stroke
				(width 0.1524)
				(type default)
			)
			(layer "F.SilkS")
		)
		(fp_line
			(start -1.525016 1.525016)
			(end -0.889 1.525016)
			(stroke
				(width 0.1524)
				(type default)
			)
			(layer "F.SilkS")
		)
		(fp_line
			(start -1.525016 1.3208)
			(end -1.525016 1.525016)
			(stroke
				(width 0.1524)
				(type default)
			)
			(layer "F.SilkS")
		)
		(fp_line
			(start -1.525016 -1.525016)
			(end -1.525016 -1.3208)
			(stroke
				(width 0.1524)
				(type default)
			)
			(layer "F.SilkS")
		)
		(fp_poly
			(pts
				(xy -2.102104 -1.112774) (xy -2.29235 -2.042414) (xy -2.812034 -1.74244)
			)
			(stroke
				(width 0)
				(type default)
			)
			(fill yes)
			(layer "F.SilkS")
		)
		(fp_line
			(start 1.525016 1.525016)
			(end -1.525016 1.525016)
			(stroke
				(width 0.1)
				(type default)
			)
			(layer "F.Fab")
		)
		(fp_line
			(start 1.525016 -1.525016)
			(end 1.525016 1.525016)
			(stroke
				(width 0.1)
				(type default)
			)
			(layer "F.Fab")
		)
		(fp_line
			(start -1.525016 1.525016)
			(end -1.525016 -1.525016)
			(stroke
				(width 0.1)
				(type default)
			)
			(layer "F.Fab")
		)
		(fp_line
			(start -1.525016 -1.525016)
			(end 1.525016 -1.525016)
			(stroke
				(width 0.1)
				(type default)
			)
			(layer "F.Fab")
		)
		(fp_poly
			(pts
				(xy -2.0701 -0.999998) (xy -2.977896 -1.302512) (xy -2.977896 -0.697484)
			)
			(stroke
				(width 0)
				(type default)
			)
			(fill yes)
			(layer "F.Fab")
		)
		(pad "1" smd rect
			(at -1.550162 -0.999998 90)
			(size 0.2794 0.9144)
			(layers "F.Cu" "F.Mask" "F.Paste")
			(net "P1V8_AUX")
		)
		(pad "2" smd rect
			(at -1.550162 -0.500126 90)
			(size 0.2794 0.9144)
			(layers "F.Cu" "F.Mask" "F.Paste")
			(net "P1V8_AUX")
		)
		(pad "3" smd rect
			(at -1.550162 0 90)
			(size 0.2794 0.9144)
			(layers "F.Cu" "F.Mask" "F.Paste")
			(net "P1V8_AUX")
		)
		(pad "4" smd rect
			(at -1.550162 0.500126 90)
			(size 0.2794 0.9144)
			(layers "F.Cu" "F.Mask" "F.Paste")
			(net "U41_ADJ")
		)
		(pad "5" smd rect
			(at -1.550162 0.999998 270)
			(size 0.2794 0.9144)
			(layers "F.Cu" "F.Mask" "F.Paste")
			(net "PWRGD_P1V8_AUX_R")
		)
		(pad "6" smd rect
			(at 1.550162 0.999998 270)
			(size 0.2794 0.9144)
			(layers "F.Cu" "F.Mask" "F.Paste")
			(net "EN_P1V8_R")
		)
		(pad "7" smd rect
			(at 1.550162 0.500126 90)
			(size 0.2794 0.9144)
			(layers "F.Cu" "F.Mask" "F.Paste")
			(net "P3V3_AUX")
		)
		(pad "8" smd rect
			(at 1.550162 0 90)
			(size 0.2794 0.9144)
			(layers "F.Cu" "F.Mask" "F.Paste")
			(net "P3V3_AUX")
		)
		(pad "9" smd rect
			(at 1.550162 -0.500126 90)
			(size 0.2794 0.9144)
			(layers "F.Cu" "F.Mask" "F.Paste")
			(net "P3V3_AUX")
		)
		(pad "10" smd rect
			(at 1.550162 -0.999998 90)
			(size 0.2794 0.9144)
			(layers "F.Cu" "F.Mask" "F.Paste")
			(net "P5V_AUX")
		)
		(pad "TH" smd rect
			(at 0 0 180)
			(size 1.7526 2.667)
			(layers "F.Cu" "F.Mask" "F.Paste")
			(net "GND")
		)
		(zone
			(layer "F.Cu")
			(hatch none 0.5)
			(connect_pads
				(clearance 0)
			)
			(min_thickness 0.25)
			(keepout
				(tracks not_allowed)
				(vias allowed)
				(pads allowed)
				(copperpour not_allowed)
				(footprints allowed)
			)
			(placement
				(enabled no)
				(sheetname "")
			)
			(fill
				(thermal_gap 0.5)
				(thermal_bridge_width 0.5)
				(island_removal_mode 0)
			)
			(polygon
				(pts
					(xy 37.685218 -54.40299) (xy 37.685218 -57.45099) (xy 35.653218 -57.45099) (xy 35.653218 -54.40299)
					(xy 37.583618 -54.40299) (xy 37.583618 -54.52999) (xy 35.729418 -54.52999) (xy 35.729418 -57.34939)
					(xy 37.609018 -57.34939) (xy 37.609018 -54.40299)
				)
			)
		)
	)
)
